(kicad_pcb
	(version 20260206)
	(generator "pcbnew")
	(generator_version "10.0")
	(general
		(thickness 1.6)
		(legacy_teardrops no)
	)
	(paper "A4")
	(title_block
		(title "03242023_DA0F0TMBIJ0_F0T_Motherboard_J_brd_V01_OCP.brd")
		(comment 1 "Grand Teton / footprints 4397-4403 of 6105")
	)
	(layers
		(0 "F.Cu" signal "TOP")
		(4 "In1.Cu" signal "GND")
		(6 "In2.Cu" signal "IN1")
		(8 "In3.Cu" signal "GND1")
		(10 "In4.Cu" signal "IN2")
		(12 "In5.Cu" signal "GND2")
		(14 "In6.Cu" signal "IN3")
		(16 "In7.Cu" signal "GND3")
		(18 "In8.Cu" signal "VCC")
		(20 "In9.Cu" signal "VCC1")
		(22 "In10.Cu" signal "GND4")
		(24 "In11.Cu" signal "IN4")
		(26 "In12.Cu" signal "GND5")
		(28 "In13.Cu" signal "IN5")
		(30 "In14.Cu" signal "GND6")
		(32 "In15.Cu" signal "IN6")
		(34 "In16.Cu" signal "GND7")
		(2 "B.Cu" signal "BOTTOM")
		(9 "F.Adhes" user "F.Adhesive")
		(11 "B.Adhes" user "B.Adhesive")
		(13 "F.Paste" user "Package Geometry/Pastemask Top")
		(15 "B.Paste" user "Package Geometry/Pastemask Bottom")
		(5 "F.SilkS" user "Ref Des/Silkscreen Top")
		(7 "B.SilkS" user "Ref Des/Silkscreen Bottom")
		(1 "F.Mask" user "Board Geometry/Soldermask Top")
		(3 "B.Mask" user "Board Geometry/Soldermask Bottom")
		(17 "Dwgs.User" user "User.Drawings")
		(19 "Cmts.User" user "User.Comments")
		(21 "Eco1.User" user "User.Eco1")
		(23 "Eco2.User" user "User.Eco2")
		(25 "Edge.Cuts" user "Board Geometry/Outline")
		(27 "Margin" user)
		(31 "F.CrtYd" user "Package Geometry/Place Bound Top")
		(29 "B.CrtYd" user "Package Geometry/Place Bound Bottom")
		(35 "F.Fab" user "Ref Des/Assembly Top")
		(33 "B.Fab" user "Ref Des/Assembly Bottom")
	)
	(footprint ""
		(layer "B.Cu")
		(at 62.246764 -318.993774 -90)
		(property "Reference" "R43"
			(at 0 0 90)
			(layer "B.SilkS")
			(hide yes)
			(effects
				(font
					(size 1.27 1.27)
				)
				(justify mirror)
			)
		)
		(property "Value" ""
			(at 0 0 90)
			(layer "B.Fab")
			(effects
				(font
					(size 1.27 1.27)
				)
				(justify mirror)
			)
		)
		(duplicate_pad_numbers_are_jumpers no)
		(fp_line
			(start -0.7874 0.4064)
			(end 0.7874 0.4064)
			(stroke
				(width 0.1524)
				(type default)
			)
			(layer "B.SilkS")
		)
		(fp_line
			(start 0.7874 0.4064)
			(end 0.7874 -0.4064)
			(stroke
				(width 0.1524)
				(type default)
			)
			(layer "B.SilkS")
		)
		(fp_line
			(start -0.7874 -0.4064)
			(end -0.7874 0.4064)
			(stroke
				(width 0.1524)
				(type default)
			)
			(layer "B.SilkS")
		)
		(fp_line
			(start 0.7874 -0.4064)
			(end -0.7874 -0.4064)
			(stroke
				(width 0.1524)
				(type default)
			)
			(layer "B.SilkS")
		)
		(fp_line
			(start -0.67945 0.3048)
			(end -0.120396 0.3048)
			(stroke
				(width 0.1)
				(type default)
			)
			(layer "B.Fab")
		)
		(fp_line
			(start -0.120396 0.3048)
			(end -0.120396 0.2794)
			(stroke
				(width 0.1)
				(type default)
			)
			(layer "B.Fab")
		)
		(fp_line
			(start 0.12065 0.3048)
			(end 0.67945 0.3048)
			(stroke
				(width 0.1)
				(type default)
			)
			(layer "B.Fab")
		)
		(fp_line
			(start 0.67945 0.3048)
			(end 0.67945 -0.305054)
			(stroke
				(width 0.1)
				(type default)
			)
			(layer "B.Fab")
		)
		(fp_line
			(start -0.120396 0.2794)
			(end 0.12065 0.2794)
			(stroke
				(width 0.1)
				(type default)
			)
			(layer "B.Fab")
		)
		(fp_line
			(start 0.12065 0.2794)
			(end 0.12065 0.3048)
			(stroke
				(width 0.1)
				(type default)
			)
			(layer "B.Fab")
		)
		(fp_line
			(start -0.12065 -0.2794)
			(end -0.12065 -0.3048)
			(stroke
				(width 0.1)
				(type default)
			)
			(layer "B.Fab")
		)
		(fp_line
			(start 0.12065 -0.2794)
			(end -0.12065 -0.2794)
			(stroke
				(width 0.1)
				(type default)
			)
			(layer "B.Fab")
		)
		(fp_line
			(start -0.67945 -0.3048)
			(end -0.67945 0.3048)
			(stroke
				(width 0.1)
				(type default)
			)
			(layer "B.Fab")
		)
		(fp_line
			(start -0.12065 -0.3048)
			(end -0.67945 -0.3048)
			(stroke
				(width 0.1)
				(type default)
			)
			(layer "B.Fab")
		)
		(fp_line
			(start 0.12065 -0.305054)
			(end 0.12065 -0.2794)
			(stroke
				(width 0.1)
				(type default)
			)
			(layer "B.Fab")
		)
		(fp_line
			(start 0.67945 -0.305054)
			(end 0.12065 -0.305054)
			(stroke
				(width 0.1)
				(type default)
			)
			(layer "B.Fab")
		)
		(pad "1" smd circle
			(at 0.40005 0 90)
			(size 0 0)
			(layers "B.Cu" "B.Mask" "B.Paste")
			(net "PD_CHA_CPU1_DIMM2_SAA")
		)
		(pad "2" smd circle
			(at -0.40005 0 90)
			(size 0 0)
			(layers "B.Cu" "B.Mask" "B.Paste")
			(net "GND")
		)
	)
	(footprint ""
		(layer "B.Cu")
		(at 62.996572 -153.08326)
		(property "Reference" "PC455_P1_1"
			(at 0 0 0)
			(layer "B.SilkS")
			(hide yes)
			(effects
				(font
					(size 1.27 1.27)
				)
				(justify mirror)
			)
		)
		(property "Value" ""
			(at 0 0 0)
			(layer "B.Fab")
			(effects
				(font
					(size 1.27 1.27)
				)
				(justify mirror)
			)
		)
		(duplicate_pad_numbers_are_jumpers no)
		(fp_line
			(start -1.524 -0.762)
			(end -1.524 0.762)
			(stroke
				(width 0.1524)
				(type default)
			)
			(layer "B.SilkS")
		)
		(fp_line
			(start -1.524 0.762)
			(end 1.524 0.762)
			(stroke
				(width 0.1524)
				(type default)
			)
			(layer "B.SilkS")
		)
		(fp_line
			(start 1.524 -0.762)
			(end -1.524 -0.762)
			(stroke
				(width 0.1524)
				(type default)
			)
			(layer "B.SilkS")
		)
		(fp_line
			(start 1.524 0.762)
			(end 1.524 -0.762)
			(stroke
				(width 0.1524)
				(type default)
			)
			(layer "B.SilkS")
		)
		(fp_line
			(start -1.1049 -0.724916)
			(end 1.1049 -0.724916)
			(stroke
				(width 0.1)
				(type default)
			)
			(layer "B.Fab")
		)
		(fp_line
			(start -1.1049 0.724916)
			(end -1.1049 -0.724916)
			(stroke
				(width 0.1)
				(type default)
			)
			(layer "B.Fab")
		)
		(fp_line
			(start 1.1049 -0.724916)
			(end 1.1049 0.724916)
			(stroke
				(width 0.1)
				(type default)
			)
			(layer "B.Fab")
		)
		(fp_line
			(start 1.1049 0.724916)
			(end -1.1049 0.724916)
			(stroke
				(width 0.1)
				(type default)
			)
			(layer "B.Fab")
		)
		(pad "1" smd rect
			(at 0.889 0)
			(size 1.016 1.27)
			(layers "B.Cu" "B.Mask" "B.Paste")
			(net "PVCCINFAON_CPU1")
		)
		(pad "2" smd rect
			(at -0.889 0)
			(size 1.016 1.27)
			(layers "B.Cu" "B.Mask" "B.Paste")
			(net "GND")
		)
	)
	(footprint ""
		(layer "B.Cu")
		(at 378.7013 -337.145884 90)
		(property "Reference" "PC259_P0_5"
			(at 0 0 90)
			(layer "B.SilkS")
			(hide yes)
			(effects
				(font
					(size 1.27 1.27)
				)
				(justify mirror)
			)
		)
		(property "Value" ""
			(at 0 0 90)
			(layer "B.Fab")
			(effects
				(font
					(size 1.27 1.27)
				)
				(justify mirror)
			)
		)
		(duplicate_pad_numbers_are_jumpers no)
		(fp_line
			(start 1.524 -0.762)
			(end -1.524 -0.762)
			(stroke
				(width 0.1524)
				(type default)
			)
			(layer "B.SilkS")
		)
		(fp_line
			(start -1.524 -0.762)
			(end -1.524 0.762)
			(stroke
				(width 0.1524)
				(type default)
			)
			(layer "B.SilkS")
		)
		(fp_line
			(start 1.524 0.762)
			(end 1.524 -0.762)
			(stroke
				(width 0.1524)
				(type default)
			)
			(layer "B.SilkS")
		)
		(fp_line
			(start -1.524 0.762)
			(end 1.524 0.762)
			(stroke
				(width 0.1524)
				(type default)
			)
			(layer "B.SilkS")
		)
		(fp_line
			(start 1.1049 -0.724916)
			(end 1.1049 0.724916)
			(stroke
				(width 0.1)
				(type default)
			)
			(layer "B.Fab")
		)
		(fp_line
			(start -1.1049 -0.724916)
			(end 1.1049 -0.724916)
			(stroke
				(width 0.1)
				(type default)
			)
			(layer "B.Fab")
		)
		(fp_line
			(start 1.1049 0.724916)
			(end -1.1049 0.724916)
			(stroke
				(width 0.1)
				(type default)
			)
			(layer "B.Fab")
		)
		(fp_line
			(start -1.1049 0.724916)
			(end -1.1049 -0.724916)
			(stroke
				(width 0.1)
				(type default)
			)
			(layer "B.Fab")
		)
		(pad "1" smd rect
			(at 0.889 0 90)
			(size 1.016 1.27)
			(layers "B.Cu" "B.Mask" "B.Paste")
			(net "SW_P12V_PVCCIN_CPU0_FLT")
		)
		(pad "2" smd rect
			(at -0.889 0 90)
			(size 1.016 1.27)
			(layers "B.Cu" "B.Mask" "B.Paste")
			(net "GND")
		)
	)
	(footprint ""
		(layer "B.Cu")
		(at 409.140152 -193.08953 -90)
		(property "Reference" "R280"
			(at 0 0 90)
			(layer "B.SilkS")
			(hide yes)
			(effects
				(font
					(size 1.27 1.27)
				)
				(justify mirror)
			)
		)
		(property "Value" ""
			(at 0 0 90)
			(layer "B.Fab")
			(effects
				(font
					(size 1.27 1.27)
				)
				(justify mirror)
			)
		)
		(duplicate_pad_numbers_are_jumpers no)
		(fp_line
			(start -0.7874 0.4064)
			(end 0.7874 0.4064)
			(stroke
				(width 0.1524)
				(type default)
			)
			(layer "B.SilkS")
		)
		(fp_line
			(start 0.7874 0.4064)
			(end 0.7874 -0.4064)
			(stroke
				(width 0.1524)
				(type default)
			)
			(layer "B.SilkS")
		)
		(fp_line
			(start -0.7874 -0.4064)
			(end -0.7874 0.4064)
			(stroke
				(width 0.1524)
				(type default)
			)
			(layer "B.SilkS")
		)
		(fp_line
			(start 0.7874 -0.4064)
			(end -0.7874 -0.4064)
			(stroke
				(width 0.1524)
				(type default)
			)
			(layer "B.SilkS")
		)
		(fp_line
			(start -0.67945 0.3048)
			(end -0.120396 0.3048)
			(stroke
				(width 0.1)
				(type default)
			)
			(layer "B.Fab")
		)
		(fp_line
			(start -0.120396 0.3048)
			(end -0.120396 0.2794)
			(stroke
				(width 0.1)
				(type default)
			)
			(layer "B.Fab")
		)
		(fp_line
			(start 0.12065 0.3048)
			(end 0.67945 0.3048)
			(stroke
				(width 0.1)
				(type default)
			)
			(layer "B.Fab")
		)
		(fp_line
			(start 0.67945 0.3048)
			(end 0.67945 -0.305054)
			(stroke
				(width 0.1)
				(type default)
			)
			(layer "B.Fab")
		)
		(fp_line
			(start -0.120396 0.2794)
			(end 0.12065 0.2794)
			(stroke
				(width 0.1)
				(type default)
			)
			(layer "B.Fab")
		)
		(fp_line
			(start 0.12065 0.2794)
			(end 0.12065 0.3048)
			(stroke
				(width 0.1)
				(type default)
			)
			(layer "B.Fab")
		)
		(fp_line
			(start -0.12065 -0.2794)
			(end -0.12065 -0.3048)
			(stroke
				(width 0.1)
				(type default)
			)
			(layer "B.Fab")
		)
		(fp_line
			(start 0.12065 -0.2794)
			(end -0.12065 -0.2794)
			(stroke
				(width 0.1)
				(type default)
			)
			(layer "B.Fab")
		)
		(fp_line
			(start -0.67945 -0.3048)
			(end -0.67945 0.3048)
			(stroke
				(width 0.1)
				(type default)
			)
			(layer "B.Fab")
		)
		(fp_line
			(start -0.12065 -0.3048)
			(end -0.67945 -0.3048)
			(stroke
				(width 0.1)
				(type default)
			)
			(layer "B.Fab")
		)
		(fp_line
			(start 0.12065 -0.305054)
			(end 0.12065 -0.2794)
			(stroke
				(width 0.1)
				(type default)
			)
			(layer "B.Fab")
		)
		(fp_line
			(start 0.67945 -0.305054)
			(end 0.12065 -0.305054)
			(stroke
				(width 0.1)
				(type default)
			)
			(layer "B.Fab")
		)
		(pad "1" smd circle
			(at 0.40005 0 90)
			(size 0 0)
			(layers "B.Cu" "B.Mask" "B.Paste")
			(net "PVNN_TERM_CPU0")
		)
		(pad "2" smd circle
			(at -0.40005 0 90)
			(size 0 0)
			(layers "B.Cu" "B.Mask" "B.Paste")
			(net "PU_CPU0_SOCKET_ID1")
		)
	)
	(footprint ""
		(layer "B.Cu")
		(at 12.666472 -184.625996)
		(property "Reference" "R2479"
			(at 0 0 0)
			(layer "B.SilkS")
			(hide yes)
			(effects
				(font
					(size 1.27 1.27)
				)
				(justify mirror)
			)
		)
		(property "Value" ""
			(at 0 0 0)
			(layer "B.Fab")
			(effects
				(font
					(size 1.27 1.27)
				)
				(justify mirror)
			)
		)
		(duplicate_pad_numbers_are_jumpers no)
		(fp_line
			(start -0.7874 -0.4064)
			(end -0.7874 0.4064)
			(stroke
				(width 0.1524)
				(type default)
			)
			(layer "B.SilkS")
		)
		(fp_line
			(start -0.7874 0.4064)
			(end 0.7874 0.4064)
			(stroke
				(width 0.1524)
				(type default)
			)
			(layer "B.SilkS")
		)
		(fp_line
			(start 0.7874 -0.4064)
			(end -0.7874 -0.4064)
			(stroke
				(width 0.1524)
				(type default)
			)
			(layer "B.SilkS")
		)
		(fp_line
			(start 0.7874 0.4064)
			(end 0.7874 -0.4064)
			(stroke
				(width 0.1524)
				(type default)
			)
			(layer "B.SilkS")
		)
		(fp_line
			(start -0.67945 -0.3048)
			(end -0.67945 0.3048)
			(stroke
				(width 0.1)
				(type default)
			)
			(layer "B.Fab")
		)
		(fp_line
			(start -0.67945 0.3048)
			(end -0.120396 0.3048)
			(stroke
				(width 0.1)
				(type default)
			)
			(layer "B.Fab")
		)
		(fp_line
			(start -0.12065 -0.3048)
			(end -0.67945 -0.3048)
			(stroke
				(width 0.1)
				(type default)
			)
			(layer "B.Fab")
		)
		(fp_line
			(start -0.12065 -0.2794)
			(end -0.12065 -0.3048)
			(stroke
				(width 0.1)
				(type default)
			)
			(layer "B.Fab")
		)
		(fp_line
			(start -0.120396 0.2794)
			(end 0.12065 0.2794)
			(stroke
				(width 0.1)
				(type default)
			)
			(layer "B.Fab")
		)
		(fp_line
			(start -0.120396 0.3048)
			(end -0.120396 0.2794)
			(stroke
				(width 0.1)
				(type default)
			)
			(layer "B.Fab")
		)
		(fp_line
			(start 0.12065 -0.305054)
			(end 0.12065 -0.2794)
			(stroke
				(width 0.1)
				(type default)
			)
			(layer "B.Fab")
		)
		(fp_line
			(start 0.12065 -0.2794)
			(end -0.12065 -0.2794)
			(stroke
				(width 0.1)
				(type default)
			)
			(layer "B.Fab")
		)
		(fp_line
			(start 0.12065 0.2794)
			(end 0.12065 0.3048)
			(stroke
				(width 0.1)
				(type default)
			)
			(layer "B.Fab")
		)
		(fp_line
			(start 0.12065 0.3048)
			(end 0.67945 0.3048)
			(stroke
				(width 0.1)
				(type default)
			)
			(layer "B.Fab")
		)
		(fp_line
			(start 0.67945 -0.305054)
			(end 0.12065 -0.305054)
			(stroke
				(width 0.1)
				(type default)
			)
			(layer "B.Fab")
		)
		(fp_line
			(start 0.67945 0.3048)
			(end 0.67945 -0.305054)
			(stroke
				(width 0.1)
				(type default)
			)
			(layer "B.Fab")
		)
		(pad "1" smd circle
			(at 0.40005 0 180)
			(size 0 0)
			(layers "B.Cu" "B.Mask" "B.Paste")
			(net "SMB_PEHPCPU1_LVC3_SCL_R0")
		)
		(pad "2" smd circle
			(at -0.40005 0 180)
			(size 0 0)
			(layers "B.Cu" "B.Mask" "B.Paste")
			(net "SMB_PEHPCPU1_LVC3_SCL")
		)
	)
	(footprint ""
		(layer "B.Cu")
		(at 380.977648 -328.65187 -90)
		(property "Reference" "PC269_P0_5"
			(at 0 0 90)
			(layer "B.SilkS")
			(hide yes)
			(effects
				(font
					(size 1.27 1.27)
				)
				(justify mirror)
			)
		)
		(property "Value" ""
			(at 0 0 90)
			(layer "B.Fab")
			(effects
				(font
					(size 1.27 1.27)
				)
				(justify mirror)
			)
		)
		(duplicate_pad_numbers_are_jumpers no)
		(fp_line
			(start -1.524 0.762)
			(end 1.524 0.762)
			(stroke
				(width 0.1524)
				(type default)
			)
			(layer "B.SilkS")
		)
		(fp_line
			(start 1.524 0.762)
			(end 1.524 -0.762)
			(stroke
				(width 0.1524)
				(type default)
			)
			(layer "B.SilkS")
		)
		(fp_line
			(start -1.524 -0.762)
			(end -1.524 0.762)
			(stroke
				(width 0.1524)
				(type default)
			)
			(layer "B.SilkS")
		)
		(fp_line
			(start 1.524 -0.762)
			(end -1.524 -0.762)
			(stroke
				(width 0.1524)
				(type default)
			)
			(layer "B.SilkS")
		)
		(fp_line
			(start -1.1049 0.724916)
			(end -1.1049 -0.724916)
			(stroke
				(width 0.1)
				(type default)
			)
			(layer "B.Fab")
		)
		(fp_line
			(start 1.1049 0.724916)
			(end -1.1049 0.724916)
			(stroke
				(width 0.1)
				(type default)
			)
			(layer "B.Fab")
		)
		(fp_line
			(start -1.1049 -0.724916)
			(end 1.1049 -0.724916)
			(stroke
				(width 0.1)
				(type default)
			)
			(layer "B.Fab")
		)
		(fp_line
			(start 1.1049 -0.724916)
			(end 1.1049 0.724916)
			(stroke
				(width 0.1)
				(type default)
			)
			(layer "B.Fab")
		)
		(pad "1" smd rect
			(at 0.889 0 270)
			(size 1.016 1.27)
			(layers "B.Cu" "B.Mask" "B.Paste")
			(net "PVCCIN_CPU0")
		)
		(pad "2" smd rect
			(at -0.889 0 270)
			(size 1.016 1.27)
			(layers "B.Cu" "B.Mask" "B.Paste")
			(net "GND")
		)
	)
	(footprint ""
		(layer "B.Cu")
		(at 256.09169 -319.48374 180)
		(property "Reference" "C20"
			(at 0 0 0)
			(layer "B.SilkS")
			(hide yes)
			(effects
				(font
					(size 1.27 1.27)
				)
				(justify mirror)
			)
		)
		(property "Value" ""
			(at 0 0 0)
			(layer "B.Fab")
			(effects
				(font
					(size 1.27 1.27)
				)
				(justify mirror)
			)
		)
		(duplicate_pad_numbers_are_jumpers no)
		(fp_line
			(start 0.7874 0.4064)
			(end 0.7874 -0.4064)
			(stroke
				(width 0.1524)
				(type default)
			)
			(layer "B.SilkS")
		)
		(fp_line
			(start 0.7874 -0.4064)
			(end -0.7874 -0.4064)
			(stroke
				(width 0.1524)
				(type default)
			)
			(layer "B.SilkS")
		)
		(fp_line
			(start -0.7874 0.4064)
			(end 0.7874 0.4064)
			(stroke
				(width 0.1524)
				(type default)
			)
			(layer "B.SilkS")
		)
		(fp_line
			(start -0.7874 -0.4064)
			(end -0.7874 0.4064)
			(stroke
				(width 0.1524)
				(type default)
			)
			(layer "B.SilkS")
		)
		(fp_line
			(start 0.67945 0.3048)
			(end 0.67945 -0.305054)
			(stroke
				(width 0.1)
				(type default)
			)
			(layer "B.Fab")
		)
		(fp_line
			(start 0.67945 -0.305054)
			(end 0.12065 -0.305054)
			(stroke
				(width 0.1)
				(type default)
			)
			(layer "B.Fab")
		)
		(fp_line
			(start 0.12065 0.3048)
			(end 0.67945 0.3048)
			(stroke
				(width 0.1)
				(type default)
			)
			(layer "B.Fab")
		)
		(fp_line
			(start 0.12065 0.2794)
			(end 0.12065 0.3048)
			(stroke
				(width 0.1)
				(type default)
			)
			(layer "B.Fab")
		)
		(fp_line
			(start 0.12065 -0.2794)
			(end -0.12065 -0.2794)
			(stroke
				(width 0.1)
				(type default)
			)
			(layer "B.Fab")
		)
		(fp_line
			(start 0.12065 -0.305054)
			(end 0.12065 -0.2794)
			(stroke
				(width 0.1)
				(type default)
			)
			(layer "B.Fab")
		)
		(fp_line
			(start -0.120396 0.3048)
			(end -0.120396 0.2794)
			(stroke
				(width 0.1)
				(type default)
			)
			(layer "B.Fab")
		)
		(fp_line
			(start -0.120396 0.2794)
			(end 0.12065 0.2794)
			(stroke
				(width 0.1)
				(type default)
			)
			(layer "B.Fab")
		)
		(fp_line
			(start -0.12065 -0.2794)
			(end -0.12065 -0.3048)
			(stroke
				(width 0.1)
				(type default)
			)
			(layer "B.Fab")
		)
		(fp_line
			(start -0.12065 -0.3048)
			(end -0.67945 -0.3048)
			(stroke
				(width 0.1)
				(type default)
			)
			(layer "B.Fab")
		)
		(fp_line
			(start -0.67945 0.3048)
			(end -0.120396 0.3048)
			(stroke
				(width 0.1)
				(type default)
			)
			(layer "B.Fab")
		)
		(fp_line
			(start -0.67945 -0.3048)
			(end -0.67945 0.3048)
			(stroke
				(width 0.1)
				(type default)
			)
			(layer "B.Fab")
		)
		(pad "1" smd circle
			(at 0.40005 0)
			(size 0 0)
			(layers "B.Cu" "B.Mask" "B.Paste")
			(net "P3V3_AUX")
		)
		(pad "2" smd circle
			(at -0.40005 0)
			(size 0 0)
			(layers "B.Cu" "B.Mask" "B.Paste")
			(net "GND")
		)
	)
)
